(kicad_pcb
	(version 20241229)
	(generator "pcbnew")
	(generator_version "9.0")
	(general
		(thickness 1.63)
		(legacy_teardrops no)
	)
	(paper "A4")
	(title_block
		(title "CM4 Baseboard")
		(date "2026-01-05")
		(rev "1.1.1")
		(company "Antmicro Ltd")
		(comment 1 "www.antmicro.com")
		(comment 9 "footprint 200 of 506 (J202), pads 100-100 of 100")
	)
	(layers
		(0 "F.Cu" signal)
		(4 "In1.Cu" power)
		(6 "In2.Cu" power)
		(8 "In3.Cu" signal)
		(10 "In4.Cu" signal)
		(2 "B.Cu" signal)
		(9 "F.Adhes" user "F.Adhesive")
		(11 "B.Adhes" user "B.Adhesive")
		(13 "F.Paste" user)
		(15 "B.Paste" user)
		(5 "F.SilkS" user "F.Silkscreen")
		(7 "B.SilkS" user "B.Silkscreen")
		(1 "F.Mask" user)
		(3 "B.Mask" user)
		(17 "Dwgs.User" user "User.Drawings")
		(19 "Cmts.User" user "User.Comments")
		(21 "Eco1.User" user "User.Eco1")
		(23 "Eco2.User" user "User.Eco2")
		(25 "Edge.Cuts" user)
		(27 "Margin" user)
		(31 "F.CrtYd" user "F.Courtyard")
		(29 "B.CrtYd" user "B.Courtyard")
		(35 "F.Fab" user)
		(33 "B.Fab" user)
	)
	(footprint "antmicro-footprints:Conn_Socket_Hirose_DF40_2x50_DF40HC-3.0-100DS-0.4V"
		(layer "F.Cu")
		(at 114.020961 154.714 -90)
		(property "Reference" "J202"
			(at -8.7975 2.432999 90)
			(layer "F.SilkS")
			(effects
				(font
					(size 0.7 0.7)
					(thickness 0.15)
				)
				(justify left bottom)
			)
		)
		(property "Value" "Socket_Hirose_DF40_2x50_DF40HC-3.0-100DS-0.4V"
			(at 0 3.25 90)
			(layer "F.Fab")
			(effects
				(font
					(size 0.7 0.7)
					(thickness 0.15)
				)
				(justify left bottom)
			)
		)
		(property "Datasheet" "https://www.hirose.com/en/product/document?clcode=CL0684-4151-0-51&productname=DF40HC(3.0)-100DS-0.4V(51&series=DF40&documenttype=Catalog&lang=en&documentid=en_DF40_CAT"
			(at 0 0 270)
			(layer "F.Fab")
			(hide yes)
			(effects
				(font
					(size 1.27 1.27)
					(thickness 0.15)
				)
			)
		)
		(property "Manufacturer" "Hirose Electric"
			(at 0 0 270)
			(unlocked yes)
			(layer "F.Fab")
			(hide yes)
			(effects
				(font
					(size 1 1)
					(thickness 0.15)
				)
			)
		)
		(property "MPN" "DF40HC(3.0)-100DS-0.4V(51)"
			(at 0 0 270)
			(unlocked yes)
			(layer "F.Fab")
			(hide yes)
			(effects
				(font
					(size 1 1)
					(thickness 0.15)
				)
			)
		)
		(property "Author" "Antmicro"
			(at 0 0 270)
			(unlocked yes)
			(layer "F.Fab")
			(hide yes)
			(effects
				(font
					(size 1 1)
					(thickness 0.15)
				)
			)
		)
		(property "License" "Apache-2.0"
			(at 0 0 270)
			(unlocked yes)
			(layer "F.Fab")
			(hide yes)
			(effects
				(font
					(size 1 1)
					(thickness 0.15)
				)
			)
		)
		(property "Pitch" "0.4 mm"
			(at 0 0 270)
			(unlocked yes)
			(layer "F.Fab")
			(hide yes)
			(effects
				(font
					(size 1 1)
					(thickness 0.15)
				)
			)
		)
		(sheetname "/Compute module/")
		(sheetfile "compute-module.kicad_sch")
		(attr smd)
		(pad "100" smd rect
			(at 9.803 -1.534 270)
			(size 0.2 0.7)
			(layers "F.Cu" "F.Mask" "F.Paste")
			(net 267 "/Compute module/HDMI.SCL")
			(pintype "passive")
		)
	)
)
